(kicad_pcb
	(version 20260206)
	(generator "pcbnew")
	(generator_version "10.0")
	(general
		(thickness 1.6)
		(legacy_teardrops no)
	)
	(paper "A4")
	(title_block
		(title "01162023_DA0F0TEBIF0_F0T_Expander_BD_F_brd_V02_OCP.brd")
		(comment 1 "Grand Teton / footprints 6053-6057 of 9728")
	)
	(layers
		(0 "F.Cu" signal "TOP")
		(4 "In1.Cu" signal "GND")
		(6 "In2.Cu" signal "VCC")
		(8 "In3.Cu" signal "VCC1")
		(10 "In4.Cu" signal "GND1")
		(12 "In5.Cu" signal "IN1")
		(14 "In6.Cu" signal "GND2")
		(16 "In7.Cu" signal "IN2")
		(18 "In8.Cu" signal "GND3")
		(20 "In9.Cu" signal "IN3")
		(22 "In10.Cu" signal "GND4")
		(24 "In11.Cu" signal "IN4")
		(26 "In12.Cu" signal "GND5")
		(28 "In13.Cu" signal "IN5")
		(30 "In14.Cu" signal "GND6")
		(32 "In15.Cu" signal "IN6")
		(34 "In16.Cu" signal "GND7")
		(2 "B.Cu" signal "BOTTOM")
		(9 "F.Adhes" user "F.Adhesive")
		(11 "B.Adhes" user "B.Adhesive")
		(13 "F.Paste" user "Package Geometry/Pastemask Top")
		(15 "B.Paste" user "Package Geometry/Pastemask Bottom")
		(5 "F.SilkS" user "Ref Des/Silkscreen Top")
		(7 "B.SilkS" user "Ref Des/Silkscreen Bottom")
		(1 "F.Mask" user "Board Geometry/Soldermask Top")
		(3 "B.Mask" user "Board Geometry/Soldermask Bottom")
		(17 "Dwgs.User" user "User.Drawings")
		(19 "Cmts.User" user "User.Comments")
		(21 "Eco1.User" user "User.Eco1")
		(23 "Eco2.User" user "User.Eco2")
		(25 "Edge.Cuts" user "Board Geometry/Outline")
		(27 "Margin" user)
		(31 "F.CrtYd" user "Package Geometry/Place Bound Top")
		(29 "B.CrtYd" user "Package Geometry/Place Bound Bottom")
		(35 "F.Fab" user "Ref Des/Assembly Top")
		(33 "B.Fab" user "Ref Des/Assembly Bottom")
	)
	(footprint ""
		(layer "F.Cu")
		(at 39.280592 -102.888796)
		(property "Reference" "C59"
			(at 0 0 0)
			(layer "F.SilkS")
			(hide yes)
			(effects
				(font
					(size 1.27 1.27)
				)
			)
		)
		(property "Value" ""
			(at 0 0 0)
			(layer "F.Fab")
			(effects
				(font
					(size 1.27 1.27)
				)
			)
		)
		(duplicate_pad_numbers_are_jumpers no)
		(fp_line
			(start -0.299974 -0.150114)
			(end 0.299974 -0.150114)
			(stroke
				(width 0.1)
				(type default)
			)
			(layer "F.Fab")
		)
		(fp_line
			(start -0.299974 0.150114)
			(end -0.299974 -0.150114)
			(stroke
				(width 0.1)
				(type default)
			)
			(layer "F.Fab")
		)
		(fp_line
			(start 0.299974 -0.150114)
			(end 0.299974 0.150114)
			(stroke
				(width 0.1)
				(type default)
			)
			(layer "F.Fab")
		)
		(fp_line
			(start 0.299974 0.150114)
			(end -0.299974 0.150114)
			(stroke
				(width 0.1)
				(type default)
			)
			(layer "F.Fab")
		)
		(pad "1" smd rect
			(at -0.2667 0)
			(size 0.3048 0.381)
			(layers "F.Cu" "F.Mask" "F.Paste")
			(net "P5E_PEX0_STN1_TX_DP<18>")
		)
		(pad "2" smd rect
			(at 0.2667 0)
			(size 0.3048 0.381)
			(layers "F.Cu" "F.Mask" "F.Paste")
			(net "P5E_PEX0_STN1_TX_C_DP<18>")
		)
	)
	(footprint ""
		(layer "F.Cu")
		(at 358.013 -219.456 180)
		(property "Reference" "R4086"
			(at 0 0 180)
			(layer "F.SilkS")
			(hide yes)
			(effects
				(font
					(size 1.27 1.27)
				)
			)
		)
		(property "Value" ""
			(at 0 0 180)
			(layer "F.Fab")
			(effects
				(font
					(size 1.27 1.27)
				)
			)
		)
		(duplicate_pad_numbers_are_jumpers no)
		(fp_line
			(start 0.7874 0.4064)
			(end -0.7874 0.4064)
			(stroke
				(width 0.1524)
				(type default)
			)
			(layer "F.SilkS")
		)
		(fp_line
			(start 0.7874 -0.4064)
			(end 0.7874 0.4064)
			(stroke
				(width 0.1524)
				(type default)
			)
			(layer "F.SilkS")
		)
		(fp_line
			(start -0.7874 0.4064)
			(end -0.7874 -0.4064)
			(stroke
				(width 0.1524)
				(type default)
			)
			(layer "F.SilkS")
		)
		(fp_line
			(start -0.7874 -0.4064)
			(end 0.7874 -0.4064)
			(stroke
				(width 0.1524)
				(type default)
			)
			(layer "F.SilkS")
		)
		(fp_line
			(start 0.67945 0.3048)
			(end 0.120396 0.3048)
			(stroke
				(width 0.1)
				(type default)
			)
			(layer "F.Fab")
		)
		(fp_line
			(start 0.67945 -0.3048)
			(end 0.67945 0.3048)
			(stroke
				(width 0.1)
				(type default)
			)
			(layer "F.Fab")
		)
		(fp_line
			(start 0.12065 -0.2794)
			(end 0.12065 -0.3048)
			(stroke
				(width 0.1)
				(type default)
			)
			(layer "F.Fab")
		)
		(fp_line
			(start 0.12065 -0.3048)
			(end 0.67945 -0.3048)
			(stroke
				(width 0.1)
				(type default)
			)
			(layer "F.Fab")
		)
		(fp_line
			(start 0.120396 0.3048)
			(end 0.120396 0.2794)
			(stroke
				(width 0.1)
				(type default)
			)
			(layer "F.Fab")
		)
		(fp_line
			(start 0.120396 0.2794)
			(end -0.12065 0.2794)
			(stroke
				(width 0.1)
				(type default)
			)
			(layer "F.Fab")
		)
		(fp_line
			(start -0.12065 0.3048)
			(end -0.67945 0.3048)
			(stroke
				(width 0.1)
				(type default)
			)
			(layer "F.Fab")
		)
		(fp_line
			(start -0.12065 0.2794)
			(end -0.12065 0.3048)
			(stroke
				(width 0.1)
				(type default)
			)
			(layer "F.Fab")
		)
		(fp_line
			(start -0.12065 -0.2794)
			(end 0.12065 -0.2794)
			(stroke
				(width 0.1)
				(type default)
			)
			(layer "F.Fab")
		)
		(fp_line
			(start -0.12065 -0.305054)
			(end -0.12065 -0.2794)
			(stroke
				(width 0.1)
				(type default)
			)
			(layer "F.Fab")
		)
		(fp_line
			(start -0.67945 0.3048)
			(end -0.67945 -0.305054)
			(stroke
				(width 0.1)
				(type default)
			)
			(layer "F.Fab")
		)
		(fp_line
			(start -0.67945 -0.305054)
			(end -0.12065 -0.305054)
			(stroke
				(width 0.1)
				(type default)
			)
			(layer "F.Fab")
		)
		(pad "1" smd circle
			(at -0.40005 0 180)
			(size 0 0)
			(layers "F.Cu" "F.Mask" "F.Paste")
			(net "RST_NIC6_PERST_R_N")
		)
		(pad "2" smd circle
			(at 0.40005 0 180)
			(size 0 0)
			(layers "F.Cu" "F.Mask" "F.Paste")
			(net "RST_NIC6_PERST_N")
		)
	)
	(footprint ""
		(layer "F.Cu")
		(at 189.474856 -406.291796 90)
		(property "Reference" "U338"
			(at -1.481328 -3.258312 0)
			(unlocked yes)
			(layer "F.SilkS")
			(effects
				(font
					(size 0.7874 0.5842)
					(thickness 0.1524)
				)
			)
		)
		(property "Value" ""
			(at 0 0 90)
			(layer "F.Fab")
			(effects
				(font
					(size 1.27 1.27)
				)
			)
		)
		(duplicate_pad_numbers_are_jumpers no)
		(fp_line
			(start 2.046478 -1.450086)
			(end 0.484886 -1.450086)
			(stroke
				(width 0.1524)
				(type default)
			)
			(layer "F.SilkS")
		)
		(fp_line
			(start 0.484886 -1.450086)
			(end 0 -0.762)
			(stroke
				(width 0.1524)
				(type default)
			)
			(layer "F.SilkS")
		)
		(fp_line
			(start -0.484886 -1.450086)
			(end -2.046478 -1.450086)
			(stroke
				(width 0.1524)
				(type default)
			)
			(layer "F.SilkS")
		)
		(fp_line
			(start -2.046478 -1.450086)
			(end -2.046478 1.450086)
			(stroke
				(width 0.1524)
				(type default)
			)
			(layer "F.SilkS")
		)
		(fp_line
			(start 0 -0.762)
			(end -0.484886 -1.450086)
			(stroke
				(width 0.1524)
				(type default)
			)
			(layer "F.SilkS")
		)
		(fp_line
			(start 2.046478 1.450086)
			(end 2.046478 -1.450086)
			(stroke
				(width 0.1524)
				(type default)
			)
			(layer "F.SilkS")
		)
		(fp_line
			(start -2.046478 1.450086)
			(end 2.046478 1.450086)
			(stroke
				(width 0.1524)
				(type default)
			)
			(layer "F.SilkS")
		)
		(fp_poly
			(pts
				(xy -3.229356 -1.693164) (xy -2.511044 -2.411476) (xy -2.151888 -1.334008)
			)
			(stroke
				(width 0)
				(type default)
			)
			(fill yes)
			(layer "F.SilkS")
		)
		(fp_line
			(start 0.87503 -1.450086)
			(end -0.87503 -1.450086)
			(stroke
				(width 0.1)
				(type default)
			)
			(layer "F.Fab")
		)
		(fp_line
			(start -0.87503 -1.450086)
			(end -0.87503 1.450086)
			(stroke
				(width 0.1)
				(type default)
			)
			(layer "F.Fab")
		)
		(fp_line
			(start 0.87503 1.450086)
			(end 0.87503 -1.450086)
			(stroke
				(width 0.1)
				(type default)
			)
			(layer "F.Fab")
		)
		(fp_line
			(start -0.87503 1.450086)
			(end 0.87503 1.450086)
			(stroke
				(width 0.1)
				(type default)
			)
			(layer "F.Fab")
		)
		(fp_poly
			(pts
				(xy -3.2512 -0.44196) (xy -3.2512 -1.45796) (xy -2.2352 -0.94996)
			)
			(stroke
				(width 0)
				(type default)
			)
			(fill yes)
			(layer "F.Fab")
		)
		(pad "1" smd rect
			(at -1.309878 -0.94996 180)
			(size 0.635 1.2192)
			(layers "F.Cu" "F.Mask" "F.Paste")
			(net "FM_UV_ADR_TRIGGER_N")
		)
		(pad "2" smd rect
			(at -1.309878 0 180)
			(size 0.635 1.2192)
			(layers "F.Cu" "F.Mask" "F.Paste")
			(net "GND")
		)
		(pad "3" smd rect
			(at -1.309878 0.94996 180)
			(size 0.635 1.2192)
			(layers "F.Cu" "F.Mask" "F.Paste")
			(net "A_P12V_AUX_ADR_TRIGGER")
		)
		(pad "4" smd rect
			(at 1.309878 0.94996 180)
			(size 0.635 1.2192)
			(layers "F.Cu" "F.Mask" "F.Paste")
			(net "A_P12V_AUX_FP_TRIGGER")
		)
		(pad "5" smd rect
			(at 1.309878 0 180)
			(size 0.635 1.2192)
			(layers "F.Cu" "F.Mask" "F.Paste")
			(net "FM_UV_LT6700_VS")
		)
		(pad "6" smd rect
			(at 1.309878 -0.94996 180)
			(size 0.635 1.2192)
			(layers "F.Cu" "F.Mask" "F.Paste")
			(net "A_P12V_AUX_FPH_GATE")
		)
	)
	(footprint ""
		(layer "F.Cu")
		(at 339.773514 -241.336322 -90)
		(property "Reference" "C2745"
			(at 0 0 270)
			(layer "F.SilkS")
			(hide yes)
			(effects
				(font
					(size 1.27 1.27)
				)
			)
		)
		(property "Value" ""
			(at 0 0 270)
			(layer "F.Fab")
			(effects
				(font
					(size 1.27 1.27)
				)
			)
		)
		(duplicate_pad_numbers_are_jumpers no)
		(fp_line
			(start -0.7874 0.4064)
			(end -0.7874 -0.4064)
			(stroke
				(width 0.1524)
				(type default)
			)
			(layer "F.SilkS")
		)
		(fp_line
			(start 0.7874 0.4064)
			(end -0.7874 0.4064)
			(stroke
				(width 0.1524)
				(type default)
			)
			(layer "F.SilkS")
		)
		(fp_line
			(start -0.7874 -0.4064)
			(end 0.7874 -0.4064)
			(stroke
				(width 0.1524)
				(type default)
			)
			(layer "F.SilkS")
		)
		(fp_line
			(start 0.7874 -0.4064)
			(end 0.7874 0.4064)
			(stroke
				(width 0.1524)
				(type default)
			)
			(layer "F.SilkS")
		)
		(fp_line
			(start -0.67945 0.3048)
			(end -0.67945 -0.305054)
			(stroke
				(width 0.1)
				(type default)
			)
			(layer "F.Fab")
		)
		(fp_line
			(start -0.12065 0.3048)
			(end -0.67945 0.3048)
			(stroke
				(width 0.1)
				(type default)
			)
			(layer "F.Fab")
		)
		(fp_line
			(start 0.120396 0.3048)
			(end 0.120396 0.2794)
			(stroke
				(width 0.1)
				(type default)
			)
			(layer "F.Fab")
		)
		(fp_line
			(start 0.67945 0.3048)
			(end 0.120396 0.3048)
			(stroke
				(width 0.1)
				(type default)
			)
			(layer "F.Fab")
		)
		(fp_line
			(start -0.12065 0.2794)
			(end -0.12065 0.3048)
			(stroke
				(width 0.1)
				(type default)
			)
			(layer "F.Fab")
		)
		(fp_line
			(start 0.120396 0.2794)
			(end -0.12065 0.2794)
			(stroke
				(width 0.1)
				(type default)
			)
			(layer "F.Fab")
		)
		(fp_line
			(start -0.12065 -0.2794)
			(end 0.12065 -0.2794)
			(stroke
				(width 0.1)
				(type default)
			)
			(layer "F.Fab")
		)
		(fp_line
			(start 0.12065 -0.2794)
			(end 0.12065 -0.3048)
			(stroke
				(width 0.1)
				(type default)
			)
			(layer "F.Fab")
		)
		(fp_line
			(start 0.12065 -0.3048)
			(end 0.67945 -0.3048)
			(stroke
				(width 0.1)
				(type default)
			)
			(layer "F.Fab")
		)
		(fp_line
			(start 0.67945 -0.3048)
			(end 0.67945 0.3048)
			(stroke
				(width 0.1)
				(type default)
			)
			(layer "F.Fab")
		)
		(fp_line
			(start -0.67945 -0.305054)
			(end -0.12065 -0.305054)
			(stroke
				(width 0.1)
				(type default)
			)
			(layer "F.Fab")
		)
		(fp_line
			(start -0.12065 -0.305054)
			(end -0.12065 -0.2794)
			(stroke
				(width 0.1)
				(type default)
			)
			(layer "F.Fab")
		)
		(pad "1" smd circle
			(at -0.40005 0 270)
			(size 0 0)
			(layers "F.Cu" "F.Mask" "F.Paste")
			(net "P3V3_AUX")
		)
		(pad "2" smd circle
			(at 0.40005 0 270)
			(size 0 0)
			(layers "F.Cu" "F.Mask" "F.Paste")
			(net "GND")
		)
	)
	(footprint ""
		(layer "F.Cu")
		(at 98.503486 -243.237258)
		(property "Reference" "U96"
			(at -0.205486 -2.328672 0)
			(unlocked yes)
			(layer "F.SilkS")
			(effects
				(font
					(size 0.7874 0.5842)
					(thickness 0.1524)
				)
			)
		)
		(property "Value" ""
			(at 0 0 0)
			(layer "F.Fab")
			(effects
				(font
					(size 1.27 1.27)
				)
			)
		)
		(duplicate_pad_numbers_are_jumpers no)
		(fp_line
			(start -1.500124 -1.500124)
			(end -1.004062 -1.500124)
			(stroke
				(width 0.1524)
				(type default)
			)
			(layer "F.SilkS")
		)
		(fp_line
			(start -1.500124 -1.004062)
			(end -1.500124 -1.500124)
			(stroke
				(width 0.1524)
				(type default)
			)
			(layer "F.SilkS")
		)
		(fp_line
			(start -1.500124 1.500124)
			(end -1.500124 1.004062)
			(stroke
				(width 0.1524)
				(type default)
			)
			(layer "F.SilkS")
		)
		(fp_line
			(start -1.004062 1.500124)
			(end -1.500124 1.500124)
			(stroke
				(width 0.1524)
				(type default)
			)
			(layer "F.SilkS")
		)
		(fp_line
			(start 1.004062 -1.500124)
			(end 1.500124 -1.500124)
			(stroke
				(width 0.1524)
				(type default)
			)
			(layer "F.SilkS")
		)
		(fp_line
			(start 1.500124 -1.500124)
			(end 1.500124 -1.004062)
			(stroke
				(width 0.1524)
				(type default)
			)
			(layer "F.SilkS")
		)
		(fp_line
			(start 1.500124 1.004062)
			(end 1.500124 1.500124)
			(stroke
				(width 0.1524)
				(type default)
			)
			(layer "F.SilkS")
		)
		(fp_line
			(start 1.500124 1.500124)
			(end 1.004062 1.500124)
			(stroke
				(width 0.1524)
				(type default)
			)
			(layer "F.SilkS")
		)
		(fp_poly
			(pts
				(xy -2.518156 -1.494282) (xy -1.64084 -1.201928) (xy -1.933194 -2.079244)
			)
			(stroke
				(width 0)
				(type default)
			)
			(fill yes)
			(layer "F.SilkS")
		)
		(fp_line
			(start -1.500124 -1.500124)
			(end 1.500124 -1.500124)
			(stroke
				(width 0.1)
				(type default)
			)
			(layer "F.Fab")
		)
		(fp_line
			(start -1.500124 1.500124)
			(end -1.500124 -1.500124)
			(stroke
				(width 0.1)
				(type default)
			)
			(layer "F.Fab")
		)
		(fp_line
			(start 1.500124 -1.500124)
			(end 1.500124 1.500124)
			(stroke
				(width 0.1)
				(type default)
			)
			(layer "F.Fab")
		)
		(fp_line
			(start 1.500124 1.500124)
			(end -1.500124 1.500124)
			(stroke
				(width 0.1)
				(type default)
			)
			(layer "F.Fab")
		)
		(fp_poly
			(pts
				(xy -2.847848 -1.258062) (xy -2.847848 -0.242062) (xy -1.831848 -0.750062)
			)
			(stroke
				(width 0)
				(type default)
			)
			(fill yes)
			(layer "F.Fab")
		)
		(pad "1" smd rect
			(at -1.400048 -0.750062 270)
			(size 0.2286 0.6096)
			(layers "F.Cu" "F.Mask" "F.Paste")
			(net "PEX_P1V8_ADC_A1")
		)
		(pad "2" smd rect
			(at -1.400048 -0.249936 270)
			(size 0.2286 0.6096)
			(layers "F.Cu" "F.Mask" "F.Paste")
			(net "PEX_P1V8_ADC_A0")
		)
		(pad "3" smd rect
			(at -1.400048 0.249936 270)
			(size 0.2286 0.6096)
			(layers "F.Cu" "F.Mask" "F.Paste")
			(net "PEX_P1V8_ADC_ALERT_N")
		)
		(pad "4" smd rect
			(at -1.400048 0.750062 270)
			(size 0.2286 0.6096)
			(layers "F.Cu" "F.Mask" "F.Paste")
			(net "SMB_PEX_P1V8_ADC_SDA")
		)
		(pad "5" smd rect
			(at -0.750062 1.400048)
			(size 0.2286 0.6096)
			(layers "F.Cu" "F.Mask" "F.Paste")
			(net "SMB_PEX_P1V8_ADC_SCL")
		)
		(pad "6" smd rect
			(at -0.249936 1.400048)
			(size 0.2286 0.6096)
			(layers "F.Cu" "F.Mask" "F.Paste")
			(net "Net_8594")
		)
		(pad "7" smd rect
			(at 0.249936 1.400048)
			(size 0.2286 0.6096)
			(layers "F.Cu" "F.Mask" "F.Paste")
			(net "Net_8593")
		)
		(pad "8" smd rect
			(at 0.750062 1.400048)
			(size 0.2286 0.6096)
			(layers "F.Cu" "F.Mask" "F.Paste")
			(net "Net_8592")
		)
		(pad "9" smd rect
			(at 1.400048 0.750062 270)
			(size 0.2286 0.6096)
			(layers "F.Cu" "F.Mask" "F.Paste")
			(net "P3V3_AUX")
		)
		(pad "10" smd rect
			(at 1.400048 0.249936 270)
			(size 0.2286 0.6096)
			(layers "F.Cu" "F.Mask" "F.Paste")
			(net "GND")
		)
		(pad "11" smd rect
			(at 1.400048 -0.249936 270)
			(size 0.2286 0.6096)
			(layers "F.Cu" "F.Mask" "F.Paste")
			(net "P1V8_PEX_R")
		)
		(pad "12" smd rect
			(at 1.400048 -0.750062 270)
			(size 0.2286 0.6096)
			(layers "F.Cu" "F.Mask" "F.Paste")
			(net "P12V_PEX_P1V8_VIN_N")
		)
		(pad "13" smd rect
			(at 0.750062 -1.400048)
			(size 0.2286 0.6096)
			(layers "F.Cu" "F.Mask" "F.Paste")
			(net "P12V_PEX_P1V8_VIN_P")
		)
		(pad "14" smd rect
			(at 0.249936 -1.400048)
			(size 0.2286 0.6096)
			(layers "F.Cu" "F.Mask" "F.Paste")
			(net "Net_8591")
		)
		(pad "15" smd rect
			(at -0.249936 -1.400048)
			(size 0.2286 0.6096)
			(layers "F.Cu" "F.Mask" "F.Paste")
			(net "Net_8590")
		)
		(pad "16" smd rect
			(at -0.750062 -1.400048)
			(size 0.2286 0.6096)
			(layers "F.Cu" "F.Mask" "F.Paste")
			(net "Net_8589")
		)
		(pad "TH" smd rect
			(at 0 0)
			(size 1.7018 1.7018)
			(layers "F.Cu" "F.Mask" "F.Paste")
			(net "GND")
		)
		(zone
			(layer "F.Cu")
			(hatch none 0.5)
			(connect_pads
				(clearance 0)
			)
			(min_thickness 0.25)
			(keepout
				(tracks not_allowed)
				(vias allowed)
				(pads allowed)
				(copperpour not_allowed)
				(footprints allowed)
			)
			(placement
				(enabled no)
				(sheetname "")
			)
			(fill
				(thermal_gap 0.5)
				(thermal_bridge_width 0.5)
				(island_removal_mode 0)
			)
			(polygon
				(pts
					(xy 97.459038 -243.262658) (xy 97.459038 -244.281706) (xy 99.547934 -244.281706) (xy 99.547934 -242.19281)
					(xy 97.459038 -242.19281) (xy 97.459038 -243.237258) (xy 97.601786 -243.237258) (xy 97.601786 -242.335558)
					(xy 99.405186 -242.335558) (xy 99.405186 -244.138958) (xy 97.601786 -244.138958) (xy 97.601786 -243.262658)
				)
			)
		)
	)
)
